# S9S_MB_2U (Grand Teton) — schematic netlist excerpt (pin names and nets, part order shuffled) for the footprints in the layout excerpt that follows; sources: Cadence DE-HDL packaged netlist, KiCad conversion of 03242023_DA0F0TMBIJ0_F0T_Motherboard_J_brd_V01_OCP.brd

C1325  Q_CAP  0.1UF 25V 10% X7R  pkg 0402  page 215 : A = FM_PLD_REV_N ; B = GND
PR3002  Q_RES  0 5% CHIP  pkg 0402LF  page 301 : A = GND ; B = AGND_HSC

(kicad_pcb
	(version 20260206)
	(generator "pcbnew")
	(generator_version "10.0")
	(general
		(thickness 1.6)
		(legacy_teardrops no)
	)
	(paper "A4")
	(title_block
		(title "03242023_DA0F0TMBIJ0_F0T_Motherboard_J_brd_V01_OCP.brd")
		(comment 1 "Grand Teton / footprints 3792-3793 of 6105")
	)
	(layers
		(0 "F.Cu" signal "TOP")
		(4 "In1.Cu" signal "GND")
		(6 "In2.Cu" signal "IN1")
		(8 "In3.Cu" signal "GND1")
		(10 "In4.Cu" signal "IN2")
		(12 "In5.Cu" signal "GND2")
		(14 "In6.Cu" signal "IN3")
		(16 "In7.Cu" signal "GND3")
		(18 "In8.Cu" signal "VCC")
		(20 "In9.Cu" signal "VCC1")
		(22 "In10.Cu" signal "GND4")
		(24 "In11.Cu" signal "IN4")
		(26 "In12.Cu" signal "GND5")
		(28 "In13.Cu" signal "IN5")
		(30 "In14.Cu" signal "GND6")
		(32 "In15.Cu" signal "IN6")
		(34 "In16.Cu" signal "GND7")
		(2 "B.Cu" signal "BOTTOM")
		(9 "F.Adhes" user "F.Adhesive")
		(11 "B.Adhes" user "B.Adhesive")
		(13 "F.Paste" user "Package Geometry/Pastemask Top")
		(15 "B.Paste" user "Package Geometry/Pastemask Bottom")
		(5 "F.SilkS" user "Ref Des/Silkscreen Top")
		(7 "B.SilkS" user "Ref Des/Silkscreen Bottom")
		(1 "F.Mask" user "Board Geometry/Soldermask Top")
		(3 "B.Mask" user "Board Geometry/Soldermask Bottom")
		(17 "Dwgs.User" user "User.Drawings")
		(19 "Cmts.User" user "User.Comments")
		(21 "Eco1.User" user "User.Eco1")
		(23 "Eco2.User" user "User.Eco2")
		(25 "Edge.Cuts" user "Board Geometry/Outline")
		(27 "Margin" user)
		(31 "F.CrtYd" user "Package Geometry/Place Bound Top")
		(29 "B.CrtYd" user "Package Geometry/Place Bound Bottom")
		(35 "F.Fab" user "Ref Des/Assembly Top")
		(33 "B.Fab" user "Ref Des/Assembly Bottom")
	)
	(footprint ""
		(layer "F.Cu")
		(at 193.38036 -124.170948)
		(property "Reference" "C1325"
			(at 0 0 0)
			(layer "F.SilkS")
			(hide yes)
			(effects
				(font
					(size 1.27 1.27)
				)
			)
		)
		(property "Value" ""
			(at 0 0 0)
			(layer "F.Fab")
			(effects
				(font
					(size 1.27 1.27)
				)
			)
		)
		(duplicate_pad_numbers_are_jumpers no)
		(fp_line
			(start -0.7874 -0.4064)
			(end 0.7874 -0.4064)
			(stroke
				(width 0.1524)
				(type default)
			)
			(layer "F.SilkS")
		)
		(fp_line
			(start -0.7874 0.4064)
			(end -0.7874 -0.4064)
			(stroke
				(width 0.1524)
				(type default)
			)
			(layer "F.SilkS")
		)
		(fp_line
			(start 0.7874 -0.4064)
			(end 0.7874 0.4064)
			(stroke
				(width 0.1524)
				(type default)
			)
			(layer "F.SilkS")
		)
		(fp_line
			(start 0.7874 0.4064)
			(end -0.7874 0.4064)
			(stroke
				(width 0.1524)
				(type default)
			)
			(layer "F.SilkS")
		)
		(fp_line
			(start -0.67945 -0.305054)
			(end -0.12065 -0.305054)
			(stroke
				(width 0.1)
				(type default)
			)
			(layer "F.Fab")
		)
		(fp_line
			(start -0.67945 0.3048)
			(end -0.67945 -0.305054)
			(stroke
				(width 0.1)
				(type default)
			)
			(layer "F.Fab")
		)
		(fp_line
			(start -0.12065 -0.305054)
			(end -0.12065 -0.2794)
			(stroke
				(width 0.1)
				(type default)
			)
			(layer "F.Fab")
		)
		(fp_line
			(start -0.12065 -0.2794)
			(end 0.12065 -0.2794)
			(stroke
				(width 0.1)
				(type default)
			)
			(layer "F.Fab")
		)
		(fp_line
			(start -0.12065 0.2794)
			(end -0.12065 0.3048)
			(stroke
				(width 0.1)
				(type default)
			)
			(layer "F.Fab")
		)
		(fp_line
			(start -0.12065 0.3048)
			(end -0.67945 0.3048)
			(stroke
				(width 0.1)
				(type default)
			)
			(layer "F.Fab")
		)
		(fp_line
			(start 0.120396 0.2794)
			(end -0.12065 0.2794)
			(stroke
				(width 0.1)
				(type default)
			)
			(layer "F.Fab")
		)
		(fp_line
			(start 0.120396 0.3048)
			(end 0.120396 0.2794)
			(stroke
				(width 0.1)
				(type default)
			)
			(layer "F.Fab")
		)
		(fp_line
			(start 0.12065 -0.3048)
			(end 0.67945 -0.3048)
			(stroke
				(width 0.1)
				(type default)
			)
			(layer "F.Fab")
		)
		(fp_line
			(start 0.12065 -0.2794)
			(end 0.12065 -0.3048)
			(stroke
				(width 0.1)
				(type default)
			)
			(layer "F.Fab")
		)
		(fp_line
			(start 0.67945 -0.3048)
			(end 0.67945 0.3048)
			(stroke
				(width 0.1)
				(type default)
			)
			(layer "F.Fab")
		)
		(fp_line
			(start 0.67945 0.3048)
			(end 0.120396 0.3048)
			(stroke
				(width 0.1)
				(type default)
			)
			(layer "F.Fab")
		)
		(pad "1" smd circle
			(at -0.40005 0)
			(size 0 0)
			(layers "F.Cu" "F.Mask" "F.Paste")
			(net "FM_PLD_REV_N")
		)
		(pad "2" smd circle
			(at 0.40005 0)
			(size 0 0)
			(layers "F.Cu" "F.Mask" "F.Paste")
			(net "GND")
		)
	)
	(footprint ""
		(layer "F.Cu")
		(at 179.352448 -402.255482)
		(property "Reference" "PR3002"
			(at 0 0 0)
			(layer "F.SilkS")
			(hide yes)
			(effects
				(font
					(size 1.27 1.27)
				)
			)
		)
		(property "Value" ""
			(at 0 0 0)
			(layer "F.Fab")
			(effects
				(font
					(size 1.27 1.27)
				)
			)
		)
		(duplicate_pad_numbers_are_jumpers no)
		(fp_line
			(start -0.7874 -0.4064)
			(end 0.7874 -0.4064)
			(stroke
				(width 0.1524)
				(type default)
			)
			(layer "F.SilkS")
		)
		(fp_line
			(start -0.7874 0.4064)
			(end -0.7874 -0.4064)
			(stroke
				(width 0.1524)
				(type default)
			)
			(layer "F.SilkS")
		)
		(fp_line
			(start 0.7874 -0.4064)
			(end 0.7874 0.4064)
			(stroke
				(width 0.1524)
				(type default)
			)
			(layer "F.SilkS")
		)
		(fp_line
			(start 0.7874 0.4064)
			(end -0.7874 0.4064)
			(stroke
				(width 0.1524)
				(type default)
			)
			(layer "F.SilkS")
		)
		(fp_line
			(start -0.67945 -0.305054)
			(end -0.12065 -0.305054)
			(stroke
				(width 0.1)
				(type default)
			)
			(layer "F.Fab")
		)
		(fp_line
			(start -0.67945 0.3048)
			(end -0.67945 -0.305054)
			(stroke
				(width 0.1)
				(type default)
			)
			(layer "F.Fab")
		)
		(fp_line
			(start -0.12065 -0.305054)
			(end -0.12065 -0.2794)
			(stroke
				(width 0.1)
				(type default)
			)
			(layer "F.Fab")
		)
		(fp_line
			(start -0.12065 -0.2794)
			(end 0.12065 -0.2794)
			(stroke
				(width 0.1)
				(type default)
			)
			(layer "F.Fab")
		)
		(fp_line
			(start -0.12065 0.2794)
			(end -0.12065 0.3048)
			(stroke
				(width 0.1)
				(type default)
			)
			(layer "F.Fab")
		)
		(fp_line
			(start -0.12065 0.3048)
			(end -0.67945 0.3048)
			(stroke
				(width 0.1)
				(type default)
			)
			(layer "F.Fab")
		)
		(fp_line
			(start 0.120396 0.2794)
			(end -0.12065 0.2794)
			(stroke
				(width 0.1)
				(type default)
			)
			(layer "F.Fab")
		)
		(fp_line
			(start 0.120396 0.3048)
			(end 0.120396 0.2794)
			(stroke
				(width 0.1)
				(type default)
			)
			(layer "F.Fab")
		)
		(fp_line
			(start 0.12065 -0.3048)
			(end 0.67945 -0.3048)
			(stroke
				(width 0.1)
				(type default)
			)
			(layer "F.Fab")
		)
		(fp_line
			(start 0.12065 -0.2794)
			(end 0.12065 -0.3048)
			(stroke
				(width 0.1)
				(type default)
			)
			(layer "F.Fab")
		)
		(fp_line
			(start 0.67945 -0.3048)
			(end 0.67945 0.3048)
			(stroke
				(width 0.1)
				(type default)
			)
			(layer "F.Fab")
		)
		(fp_line
			(start 0.67945 0.3048)
			(end 0.120396 0.3048)
			(stroke
				(width 0.1)
				(type default)
			)
			(layer "F.Fab")
		)
		(pad "1" smd circle
			(at -0.40005 0)
			(size 0 0)
			(layers "F.Cu" "F.Mask" "F.Paste")
			(net "GND")
		)
		(pad "2" smd circle
			(at 0.40005 0)
			(size 0 0)
			(layers "F.Cu" "F.Mask" "F.Paste")
			(net "AGND_HSC")
		)
	)
)
